# T6G (Grand Teton) — schematic netlist excerpt (pin names and nets, part order shuffled) for the footprints in the layout excerpt that follows; sources: Cadence DE-HDL packaged netlist, KiCad conversion of 04192023_DAF0TMB3IC0_F0TG_MB_C_brd_V02_OCP.brd

C1054  Q_CAP  4.7UF 6.3V 20% X6S  pkg 0402  page 312 : A = P0V9_CPU0_RT3_2A ; B = GND
C805  Q_CAP  22UF 4V 20% X6S  pkg C0402  page 301 : A = P0V9_CPU0_RT_2D ; B = GND

(kicad_pcb
	(version 20260206)
	(generator "pcbnew")
	(generator_version "10.0")
	(general
		(thickness 1.6)
		(legacy_teardrops no)
	)
	(paper "A4")
	(title_block
		(title "04192023_DAF0TMB3IC0_F0TG_MB_C_brd_V02_OCP.brd")
		(comment 1 "Grand Teton / footprints 5259-5260 of 8354")
	)
	(layers
		(0 "F.Cu" signal "TOP")
		(4 "In1.Cu" signal "GND")
		(6 "In2.Cu" signal "IN1")
		(8 "In3.Cu" signal "GND1")
		(10 "In4.Cu" signal "IN2")
		(12 "In5.Cu" signal "GND2")
		(14 "In6.Cu" signal "IN3")
		(16 "In7.Cu" signal "GND3")
		(18 "In8.Cu" signal "VCC")
		(20 "In9.Cu" signal "VCC1")
		(22 "In10.Cu" signal "GND4")
		(24 "In11.Cu" signal "IN4")
		(26 "In12.Cu" signal "GND5")
		(28 "In13.Cu" signal "IN5")
		(30 "In14.Cu" signal "GND6")
		(32 "In15.Cu" signal "IN6")
		(34 "In16.Cu" signal "GND7")
		(2 "B.Cu" signal "BOTTOM")
		(9 "F.Adhes" user "F.Adhesive")
		(11 "B.Adhes" user "B.Adhesive")
		(13 "F.Paste" user "Package Geometry/Pastemask Top")
		(15 "B.Paste" user "Package Geometry/Pastemask Bottom")
		(5 "F.SilkS" user "Ref Des/Silkscreen Top")
		(7 "B.SilkS" user "Ref Des/Silkscreen Bottom")
		(1 "F.Mask" user "Board Geometry/Soldermask Top")
		(3 "B.Mask" user "Board Geometry/Soldermask Bottom")
		(17 "Dwgs.User" user "User.Drawings")
		(19 "Cmts.User" user "User.Comments")
		(21 "Eco1.User" user "User.Eco1")
		(23 "Eco2.User" user "User.Eco2")
		(25 "Edge.Cuts" user "Board Geometry/Outline")
		(27 "Margin" user)
		(31 "F.CrtYd" user "Package Geometry/Place Bound Top")
		(29 "B.CrtYd" user "Package Geometry/Place Bound Bottom")
		(35 "F.Fab" user "Ref Des/Assembly Top")
		(33 "B.Fab" user "Ref Des/Assembly Bottom")
	)
	(footprint ""
		(layer "B.Cu")
		(at 413.819086 -398.942052 90)
		(property "Reference" "C805"
			(at 0 0 90)
			(layer "B.SilkS")
			(hide yes)
			(effects
				(font
					(size 1.27 1.27)
				)
				(justify mirror)
			)
		)
		(property "Value" ""
			(at 0 0 90)
			(layer "B.Fab")
			(effects
				(font
					(size 1.27 1.27)
				)
				(justify mirror)
			)
		)
		(duplicate_pad_numbers_are_jumpers no)
		(fp_line
			(start 0.7874 -0.4064)
			(end -0.7874 -0.4064)
			(stroke
				(width 0.1524)
				(type default)
			)
			(layer "B.SilkS")
		)
		(fp_line
			(start -0.7874 -0.4064)
			(end -0.7874 0.4064)
			(stroke
				(width 0.1524)
				(type default)
			)
			(layer "B.SilkS")
		)
		(fp_line
			(start 0.7874 0.4064)
			(end 0.7874 -0.4064)
			(stroke
				(width 0.1524)
				(type default)
			)
			(layer "B.SilkS")
		)
		(fp_line
			(start -0.7874 0.4064)
			(end 0.7874 0.4064)
			(stroke
				(width 0.1524)
				(type default)
			)
			(layer "B.SilkS")
		)
		(fp_line
			(start 0.67945 -0.305054)
			(end 0.12065 -0.305054)
			(stroke
				(width 0.1)
				(type default)
			)
			(layer "B.Fab")
		)
		(fp_line
			(start 0.12065 -0.305054)
			(end 0.12065 -0.2794)
			(stroke
				(width 0.1)
				(type default)
			)
			(layer "B.Fab")
		)
		(fp_line
			(start -0.12065 -0.3048)
			(end -0.67945 -0.3048)
			(stroke
				(width 0.1)
				(type default)
			)
			(layer "B.Fab")
		)
		(fp_line
			(start -0.67945 -0.3048)
			(end -0.67945 0.3048)
			(stroke
				(width 0.1)
				(type default)
			)
			(layer "B.Fab")
		)
		(fp_line
			(start 0.12065 -0.2794)
			(end -0.12065 -0.2794)
			(stroke
				(width 0.1)
				(type default)
			)
			(layer "B.Fab")
		)
		(fp_line
			(start -0.12065 -0.2794)
			(end -0.12065 -0.3048)
			(stroke
				(width 0.1)
				(type default)
			)
			(layer "B.Fab")
		)
		(fp_line
			(start 0.12065 0.2794)
			(end 0.12065 0.3048)
			(stroke
				(width 0.1)
				(type default)
			)
			(layer "B.Fab")
		)
		(fp_line
			(start -0.120396 0.2794)
			(end 0.12065 0.2794)
			(stroke
				(width 0.1)
				(type default)
			)
			(layer "B.Fab")
		)
		(fp_line
			(start 0.67945 0.3048)
			(end 0.67945 -0.305054)
			(stroke
				(width 0.1)
				(type default)
			)
			(layer "B.Fab")
		)
		(fp_line
			(start 0.12065 0.3048)
			(end 0.67945 0.3048)
			(stroke
				(width 0.1)
				(type default)
			)
			(layer "B.Fab")
		)
		(fp_line
			(start -0.120396 0.3048)
			(end -0.120396 0.2794)
			(stroke
				(width 0.1)
				(type default)
			)
			(layer "B.Fab")
		)
		(fp_line
			(start -0.67945 0.3048)
			(end -0.120396 0.3048)
			(stroke
				(width 0.1)
				(type default)
			)
			(layer "B.Fab")
		)
		(pad "1" smd circle
			(at 0.40005 0 270)
			(size 0 0)
			(layers "B.Cu" "B.Mask" "B.Paste")
			(net "P0V9_CPU0_RT_2D")
		)
		(pad "2" smd circle
			(at -0.40005 0 270)
			(size 0 0)
			(layers "B.Cu" "B.Mask" "B.Paste")
			(net "GND")
		)
	)
	(footprint ""
		(layer "B.Cu")
		(at 369.587272 -399.722848 -90)
		(property "Reference" "C1054"
			(at 0 0 90)
			(layer "B.SilkS")
			(hide yes)
			(effects
				(font
					(size 1.27 1.27)
				)
				(justify mirror)
			)
		)
		(property "Value" ""
			(at 0 0 90)
			(layer "B.Fab")
			(effects
				(font
					(size 1.27 1.27)
				)
				(justify mirror)
			)
		)
		(duplicate_pad_numbers_are_jumpers no)
		(fp_line
			(start -0.7874 0.4064)
			(end 0.7874 0.4064)
			(stroke
				(width 0.1524)
				(type default)
			)
			(layer "B.SilkS")
		)
		(fp_line
			(start 0.7874 0.4064)
			(end 0.7874 -0.4064)
			(stroke
				(width 0.1524)
				(type default)
			)
			(layer "B.SilkS")
		)
		(fp_line
			(start -0.7874 -0.4064)
			(end -0.7874 0.4064)
			(stroke
				(width 0.1524)
				(type default)
			)
			(layer "B.SilkS")
		)
		(fp_line
			(start 0.7874 -0.4064)
			(end -0.7874 -0.4064)
			(stroke
				(width 0.1524)
				(type default)
			)
			(layer "B.SilkS")
		)
		(fp_line
			(start -0.67945 0.3048)
			(end -0.120396 0.3048)
			(stroke
				(width 0.1)
				(type default)
			)
			(layer "B.Fab")
		)
		(fp_line
			(start -0.120396 0.3048)
			(end -0.120396 0.2794)
			(stroke
				(width 0.1)
				(type default)
			)
			(layer "B.Fab")
		)
		(fp_line
			(start 0.12065 0.3048)
			(end 0.67945 0.3048)
			(stroke
				(width 0.1)
				(type default)
			)
			(layer "B.Fab")
		)
		(fp_line
			(start 0.67945 0.3048)
			(end 0.67945 -0.305054)
			(stroke
				(width 0.1)
				(type default)
			)
			(layer "B.Fab")
		)
		(fp_line
			(start -0.120396 0.2794)
			(end 0.12065 0.2794)
			(stroke
				(width 0.1)
				(type default)
			)
			(layer "B.Fab")
		)
		(fp_line
			(start 0.12065 0.2794)
			(end 0.12065 0.3048)
			(stroke
				(width 0.1)
				(type default)
			)
			(layer "B.Fab")
		)
		(fp_line
			(start -0.12065 -0.2794)
			(end -0.12065 -0.3048)
			(stroke
				(width 0.1)
				(type default)
			)
			(layer "B.Fab")
		)
		(fp_line
			(start 0.12065 -0.2794)
			(end -0.12065 -0.2794)
			(stroke
				(width 0.1)
				(type default)
			)
			(layer "B.Fab")
		)
		(fp_line
			(start -0.67945 -0.3048)
			(end -0.67945 0.3048)
			(stroke
				(width 0.1)
				(type default)
			)
			(layer "B.Fab")
		)
		(fp_line
			(start -0.12065 -0.3048)
			(end -0.67945 -0.3048)
			(stroke
				(width 0.1)
				(type default)
			)
			(layer "B.Fab")
		)
		(fp_line
			(start 0.12065 -0.305054)
			(end 0.12065 -0.2794)
			(stroke
				(width 0.1)
				(type default)
			)
			(layer "B.Fab")
		)
		(fp_line
			(start 0.67945 -0.305054)
			(end 0.12065 -0.305054)
			(stroke
				(width 0.1)
				(type default)
			)
			(layer "B.Fab")
		)
		(pad "1" smd circle
			(at 0.40005 0 90)
			(size 0 0)
			(layers "B.Cu" "B.Mask" "B.Paste")
			(net "P0V9_CPU0_RT3_2A")
		)
		(pad "2" smd circle
			(at -0.40005 0 90)
			(size 0 0)
			(layers "B.Cu" "B.Mask" "B.Paste")
			(net "GND")
		)
	)
)
